# TIMECARD (Time Appliance Project (Time Card)) — schematic netlist excerpt (pin names and nets, part order shuffled) for the footprints in the layout excerpt that follows; sources: Cadence DE-HDL packaged netlist, KiCad conversion of R4006-B0001-02_R01.brd

MAC_PIN7  NUT  pkg P_NUT_079C100  page 21 : \1\ = R_MAC_UART_TX_FPGA_RX
C268  CAPACITOR  0.1UF 10V 10%  pkg SMC_0402R_H022  page 29 : \1\ = XP1R0V_FPGA ; \2\ = SG
TP15  TP_PIONT  pkg TP010CT020B030_PTH  page 25 : \1\ = GPS_RST_N

(kicad_pcb
	(version 20260206)
	(generator "pcbnew")
	(generator_version "10.0")
	(general
		(thickness 1.6)
		(legacy_teardrops no)
	)
	(paper "A4")
	(title_block
		(title "timecard-production-celestica-r4006 — R4006-B0001-02_R01.brd")
		(comment 1 "Time Appliance Project (Time Card) / footprints 558-560 of 1113")
	)
	(layers
		(0 "F.Cu" signal "TOP")
		(4 "In1.Cu" signal "L02_GND1")
		(6 "In2.Cu" signal "L03_SIG1")
		(8 "In3.Cu" signal "L04_GND2")
		(10 "In4.Cu" signal "L05_VCC1")
		(12 "In5.Cu" signal "L06_VCC2")
		(14 "In6.Cu" signal "L07_GND3")
		(16 "In7.Cu" signal "L08_SIG2")
		(18 "In8.Cu" signal "L09_GND4")
		(2 "B.Cu" signal "BOTTOM")
		(9 "F.Adhes" user "F.Adhesive")
		(11 "B.Adhes" user "B.Adhesive")
		(13 "F.Paste" user "Package Geometry/Pastemask Top")
		(15 "B.Paste" user "Package Geometry/Pastemask Bottom")
		(5 "F.SilkS" user "Ref Des/Silkscreen Top")
		(7 "B.SilkS" user "Ref Des/Silkscreen Bottom")
		(1 "F.Mask" user "Board Geometry/Soldermask Top")
		(3 "B.Mask" user "Board Geometry/Soldermask Bottom")
		(17 "Dwgs.User" user "User.Drawings")
		(19 "Cmts.User" user "User.Comments")
		(21 "Eco1.User" user "User.Eco1")
		(23 "Eco2.User" user "User.Eco2")
		(25 "Edge.Cuts" user "Board Geometry/Outline")
		(27 "Margin" user)
		(31 "F.CrtYd" user "Package Geometry/Place Bound Top")
		(29 "B.CrtYd" user "Package Geometry/Place Bound Bottom")
		(35 "F.Fab" user "Ref Des/Assembly Top")
		(33 "B.Fab" user "Ref Des/Assembly Bottom")
	)
	(footprint ""
		(layer "F.Cu")
		(at 137.414 -46.101 90)
		(property "Reference" "C268"
			(at 3.302 -0.08763 90)
			(unlocked yes)
			(layer "F.SilkS")
			(effects
				(font
					(size 0.7874 0.5842)
					(thickness 0.1524)
				)
			)
		)
		(property "Value" "VAL*"
			(at 0.0762 2.067306 90)
			(unlocked yes)
			(layer "F.Fab")
			(hide yes)
			(effects
				(font
					(size 0.7874 0.5842)
					(thickness 0.1524)
				)
			)
		)
		(property "Device Type" "CAPACITOR-G105-0B104-CK,0.1UF,A"
			(at 0.0508 1.127506 90)
			(unlocked yes)
			(layer "F.Fab")
			(hide yes)
			(effects
				(font
					(size 0.7874 0.5842)
					(thickness 0.1524)
				)
			)
		)
		(property "User Part Number" "PARTNUM*"
			(at 0.1016 4.023106 90)
			(unlocked yes)
			(layer "Cmts.User")
			(hide yes)
			(effects
				(font
					(size 0.7874 0.5842)
					(thickness 0.1524)
				)
			)
		)
		(property "Tolerance" "TOL*"
			(at 0.0762 3.032506 90)
			(unlocked yes)
			(layer "Cmts.User")
			(hide yes)
			(effects
				(font
					(size 0.7874 0.5842)
					(thickness 0.1524)
				)
			)
		)
		(duplicate_pad_numbers_are_jumpers no)
		(fp_line
			(start 1.143 -0.5588)
			(end -1.143 -0.5588)
			(stroke
				(width 0.1)
				(type default)
			)
			(layer "F.SilkS")
		)
		(fp_line
			(start -1.143 -0.5588)
			(end -1.143 0.5588)
			(stroke
				(width 0.1)
				(type default)
			)
			(layer "F.SilkS")
		)
		(fp_line
			(start 1.143 0.5588)
			(end 1.143 -0.5588)
			(stroke
				(width 0.1)
				(type default)
			)
			(layer "F.SilkS")
		)
		(fp_line
			(start -1.143 0.5588)
			(end 1.143 0.5588)
			(stroke
				(width 0.1)
				(type default)
			)
			(layer "F.SilkS")
		)
		(fp_rect
			(start -1.143 -0.5588)
			(end 1.143 0.5588)
			(stroke
				(width 0)
				(type default)
			)
			(fill no)
			(layer "F.CrtYd")
		)
		(fp_line
			(start 0.508 -0.3048)
			(end -0.508 -0.3048)
			(stroke
				(width 0.1)
				(type default)
			)
			(layer "F.Fab")
		)
		(fp_line
			(start -0.508 -0.3048)
			(end -0.508 0.3048)
			(stroke
				(width 0.1)
				(type default)
			)
			(layer "F.Fab")
		)
		(fp_line
			(start 0.508 0.3048)
			(end 0.508 -0.3048)
			(stroke
				(width 0.1)
				(type default)
			)
			(layer "F.Fab")
		)
		(fp_line
			(start -0.508 0.3048)
			(end 0.508 0.3048)
			(stroke
				(width 0.1)
				(type default)
			)
			(layer "F.Fab")
		)
		(pad "1" smd rect
			(at -0.5334 0 90)
			(size 0.7112 0.6096)
			(layers "F.Cu" "F.Mask" "F.Paste")
			(net "XP1R0V_FPGA")
		)
		(pad "2" smd rect
			(at 0.5334 0 90)
			(size 0.7112 0.6096)
			(layers "F.Cu" "F.Mask" "F.Paste")
			(net "SG")
		)
		(zone
			(layer "F.Cu")
			(hatch none 0.5)
			(connect_pads
				(clearance 0)
			)
			(min_thickness 0.25)
			(keepout
				(tracks allowed)
				(vias not_allowed)
				(pads allowed)
				(copperpour not_allowed)
				(footprints allowed)
			)
			(placement
				(enabled no)
				(sheetname "")
			)
			(fill
				(thermal_gap 0.5)
				(thermal_bridge_width 0.5)
				(island_removal_mode 0)
			)
			(polygon
				(pts
					(xy 137.1092 -46.0248) (xy 137.7188 -46.0248) (xy 137.7188 -46.1772) (xy 137.1092 -46.1772)
				)
			)
		)
	)
	(footprint ""
		(layer "F.Cu")
		(at 67.555618 -23.734522)
		(property "Reference" "MAC_PIN7"
			(at -0.634238 2.580132 0)
			(unlocked yes)
			(layer "F.SilkS")
			(effects
				(font
					(size 0.7874 0.5842)
					(thickness 0.1524)
				)
			)
		)
		(property "Value" ""
			(at 0 0 0)
			(layer "F.Fab")
			(effects
				(font
					(size 1.27 1.27)
				)
			)
		)
		(property "Device Type" "NUT-A200-00029-FB"
			(at 0 2.632964 0)
			(unlocked yes)
			(layer "F.Fab")
			(hide yes)
			(effects
				(font
					(size 0.7874 0.5842)
					(thickness 0.1524)
				)
			)
		)
		(property "User Part Number" "PARTNUM*"
			(at 0 3.826764 0)
			(unlocked yes)
			(layer "Cmts.User")
			(hide yes)
			(effects
				(font
					(size 0.7874 0.5842)
					(thickness 0.1524)
				)
			)
		)
		(duplicate_pad_numbers_are_jumpers no)
		(fp_circle
			(center 0 0)
			(end 1.524 0)
			(stroke
				(width 0.1)
				(type default)
			)
			(fill no)
			(layer "F.SilkS")
		)
		(fp_poly
			(pts
				(arc
					(start -1.260856 -0.1524)
					(mid -0.898049 -0.898049)
					(end -0.1524 -1.260856)
				)
				(arc
					(start -0.1524 -0.991616)
					(mid -0.709411 -0.709411)
					(end -0.991616 -0.1524)
				)
			)
			(stroke
				(width 0)
				(type default)
			)
			(fill yes)
			(layer "F.Paste")
		)
		(fp_poly
			(pts
				(arc
					(start -0.1524 1.260856)
					(mid -0.898049 0.898049)
					(end -1.260856 0.1524)
				)
				(arc
					(start -0.991616 0.1524)
					(mid -0.709411 0.709411)
					(end -0.1524 0.991616)
				)
			)
			(stroke
				(width 0)
				(type default)
			)
			(fill yes)
			(layer "F.Paste")
		)
		(fp_poly
			(pts
				(arc
					(start 0.1524 -1.260856)
					(mid 0.898049 -0.898049)
					(end 1.260856 -0.1524)
				)
				(arc
					(start 0.991616 -0.1524)
					(mid 0.709411 -0.709411)
					(end 0.1524 -0.991616)
				)
			)
			(stroke
				(width 0)
				(type default)
			)
			(fill yes)
			(layer "F.Paste")
		)
		(fp_poly
			(pts
				(arc
					(start 1.260856 0.1524)
					(mid 0.898049 0.898049)
					(end 0.1524 1.260856)
				)
				(arc
					(start 0.1524 0.991616)
					(mid 0.709411 0.709411)
					(end 0.991616 0.1524)
				)
			)
			(stroke
				(width 0)
				(type default)
			)
			(fill yes)
			(layer "F.Paste")
		)
		(fp_poly
			(pts
				(arc
					(start 6.35 0)
					(mid -6.35 0)
					(end 6.35 0)
				)
			)
			(stroke
				(width 0)
				(type default)
			)
			(fill no)
			(layer "B.CrtYd")
		)
		(fp_poly
			(pts
				(arc
					(start 1.778 0)
					(mid -1.778 0)
					(end 1.778 0)
				)
			)
			(stroke
				(width 0)
				(type default)
			)
			(fill no)
			(layer "F.CrtYd")
		)
		(fp_circle
			(center 0 0)
			(end 1.1684 0)
			(stroke
				(width 0.1)
				(type default)
			)
			(fill no)
			(layer "F.Fab")
		)
		(pad "1" thru_hole circle
			(at 0 0)
			(size 2.54 2.54)
			(drill 2.0066)
			(layers "*.Cu" "*.Mask")
			(remove_unused_layers no)
			(net "R_MAC_UART_TX_FPGA_RX")
			(thermal_gap 0.0254)
			(padstack
				(mode front_inner_back)
				(layer "Inner"
					(shape circle)
					(size 2.54 2.54)
					(clearance 0.0254)
				)
				(layer "B.Cu"
					(shape circle)
					(size 2.54 2.54)
				)
			)
		)
	)
	(footprint ""
		(layer "F.Cu")
		(at 118.618 -90.297)
		(property "Reference" "TP15"
			(at -1.9812 1.30937 0)
			(unlocked yes)
			(layer "F.SilkS")
			(effects
				(font
					(size 0.7874 0.5842)
					(thickness 0.1524)
				)
				(justify left)
			)
		)
		(property "Value" ""
			(at 0 0 0)
			(layer "F.Fab")
			(effects
				(font
					(size 1.27 1.27)
				)
			)
		)
		(property "Device Type" "TP_PIONT-TP010CT020B030_PTH-TPA"
			(at -1.341882 0.996696 0)
			(unlocked yes)
			(layer "F.Fab")
			(hide yes)
			(effects
				(font
					(size 0.7874 0.5842)
					(thickness 0.000001)
				)
				(justify left)
			)
		)
		(duplicate_pad_numbers_are_jumpers no)
		(fp_poly
			(pts
				(arc
					(start 0.889 0)
					(mid -0.889 0)
					(end 0.889 0)
				)
			)
			(stroke
				(width 0)
				(type default)
			)
			(fill no)
			(layer "B.CrtYd")
		)
		(fp_poly
			(pts
				(arc
					(start 0.889 0)
					(mid -0.889 0)
					(end 0.889 0)
				)
			)
			(stroke
				(width 0)
				(type default)
			)
			(fill no)
			(layer "F.CrtYd")
		)
		(pad "1" thru_hole circle
			(at 0 0)
			(size 0.508 0.508)
			(drill 0.254)
			(layers "*.Cu" "*.Mask")
			(remove_unused_layers no)
			(net "GPS_RST_N")
			(clearance 0.1016)
			(padstack
				(mode front_inner_back)
				(layer "Inner"
					(shape circle)
					(size 0.508 0.508)
					(clearance 0.1016)
				)
				(layer "B.Cu"
					(shape circle)
					(size 0.762 0.762)
					(clearance -0.0254)
				)
			)
		)
	)
)
